G04*
G04 #@! TF.GenerationSoftware,Altium Limited,Altium Designer,22.4.2 (48)*
G04*
G04 Layer_Physical_Order=4*
G04 Layer_Color=16711680*
%FSLAX25Y25*%
%MOIN*%
G70*
G04*
G04 #@! TF.SameCoordinates,B69760C6-9901-4916-8BAC-4CFDAA04743E*
G04*
G04*
G04 #@! TF.FilePolarity,Positive*
G04*
G01*
G75*
%ADD58C,0.02400*%
G36*
X260531Y123977D02*
X261155Y123852D01*
X261743Y123609D01*
X262272Y123256D01*
X262722Y122806D01*
X263076Y122277D01*
X263320Y121689D01*
X263445Y121065D01*
X263445Y120747D01*
X263433Y3996D01*
X263433Y3996D01*
X263433Y3996D01*
X263433Y3701D01*
X263318Y3124D01*
X263093Y2579D01*
X262766Y2090D01*
X262350Y1673D01*
X261860Y1345D01*
X261316Y1120D01*
X260738Y1004D01*
X260444Y1004D01*
X4114Y1020D01*
X4114Y1020D01*
X4114Y1020D01*
X3809D01*
X3212Y1139D01*
X2648Y1372D01*
X2142Y1710D01*
X1710Y2142D01*
X1372Y2648D01*
X1139Y3212D01*
X1020Y3809D01*
Y4114D01*
X1020Y4114D01*
X1020Y4114D01*
X1012Y120772D01*
D01*
X1012Y121086D01*
X1134Y121704D01*
X1375Y122285D01*
X1725Y122809D01*
X2169Y123254D01*
X2692Y123604D01*
X3274Y123845D01*
X3891Y123968D01*
X4206Y123969D01*
D01*
X260213Y123977D01*
X260531Y123977D01*
D02*
G37*
%LPC*%
G36*
X138058Y113000D02*
X137342D01*
X136680Y112726D01*
X136174Y112220D01*
X135900Y111558D01*
Y110842D01*
X136174Y110180D01*
X136680Y109674D01*
X137342Y109400D01*
X138058D01*
X138720Y109674D01*
X139226Y110180D01*
X139500Y110842D01*
Y111558D01*
X139226Y112220D01*
X138720Y112726D01*
X138058Y113000D01*
D02*
G37*
G36*
X250014Y120886D02*
X248812D01*
X248714Y120866D01*
X248613D01*
X247434Y120632D01*
X247342Y120593D01*
X247243Y120574D01*
X246133Y120114D01*
X246049Y120058D01*
X245956Y120019D01*
X244957Y119351D01*
X244886Y119281D01*
X244802Y119225D01*
X243952Y118375D01*
X243897Y118291D01*
X243826Y118220D01*
X243158Y117221D01*
X243119Y117128D01*
X243064Y117044D01*
X242604Y115934D01*
X242584Y115835D01*
X242546Y115743D01*
X242311Y114564D01*
Y114463D01*
X242291Y114365D01*
Y113764D01*
Y113163D01*
X242311Y113064D01*
Y112964D01*
X242546Y111785D01*
X242584Y111692D01*
X242604Y111594D01*
X243064Y110483D01*
X243119Y110399D01*
X243158Y110307D01*
X243826Y109307D01*
X243897Y109236D01*
X243952Y109153D01*
X244802Y108303D01*
X244886Y108247D01*
X244957Y108176D01*
X245956Y107508D01*
X246049Y107470D01*
X246133Y107414D01*
X247243Y106954D01*
X247342Y106934D01*
X247434Y106896D01*
X248613Y106661D01*
X248714D01*
X248812Y106642D01*
X250014D01*
X250113Y106661D01*
X250213D01*
X251392Y106896D01*
X251485Y106934D01*
X251584Y106954D01*
X252694Y107414D01*
X252778Y107470D01*
X252870Y107508D01*
X253870Y108176D01*
X253941Y108247D01*
X254024Y108303D01*
X254874Y109153D01*
X254930Y109236D01*
X255001Y109307D01*
X255669Y110307D01*
X255707Y110399D01*
X255763Y110483D01*
X256223Y111594D01*
X256243Y111692D01*
X256281Y111785D01*
X256516Y112964D01*
Y113064D01*
X256535Y113163D01*
Y113764D01*
Y114365D01*
X256516Y114463D01*
Y114564D01*
X256281Y115743D01*
X256243Y115835D01*
X256223Y115934D01*
X255763Y117044D01*
X255707Y117128D01*
X255669Y117221D01*
X255001Y118220D01*
X254930Y118291D01*
X254874Y118375D01*
X254024Y119225D01*
X253941Y119281D01*
X253870Y119351D01*
X252870Y120019D01*
X252778Y120058D01*
X252694Y120114D01*
X251584Y120574D01*
X251485Y120593D01*
X251392Y120632D01*
X250213Y120866D01*
X250113D01*
X250014Y120886D01*
D02*
G37*
G36*
X11825D02*
X10623D01*
X10525Y120866D01*
X10424D01*
X9245Y120632D01*
X9153Y120593D01*
X9054Y120574D01*
X7944Y120114D01*
X7860Y120058D01*
X7767Y120019D01*
X6768Y119351D01*
X6697Y119281D01*
X6613Y119225D01*
X5763Y118375D01*
X5708Y118291D01*
X5637Y118220D01*
X4969Y117221D01*
X4930Y117128D01*
X4875Y117044D01*
X4415Y115934D01*
X4395Y115835D01*
X4357Y115743D01*
X4122Y114564D01*
Y114463D01*
X4103Y114365D01*
Y113764D01*
Y113163D01*
X4122Y113064D01*
Y112964D01*
X4357Y111785D01*
X4395Y111692D01*
X4415Y111594D01*
X4875Y110483D01*
X4930Y110399D01*
X4969Y110307D01*
X5637Y109307D01*
X5708Y109236D01*
X5763Y109153D01*
X6613Y108303D01*
X6697Y108247D01*
X6768Y108176D01*
X7767Y107508D01*
X7860Y107470D01*
X7944Y107414D01*
X9054Y106954D01*
X9153Y106934D01*
X9245Y106896D01*
X10424Y106661D01*
X10525D01*
X10623Y106642D01*
X11825D01*
X11924Y106661D01*
X12024D01*
X13203Y106896D01*
X13296Y106934D01*
X13395Y106954D01*
X14505Y107414D01*
X14589Y107470D01*
X14681Y107508D01*
X15681Y108176D01*
X15752Y108247D01*
X15835Y108303D01*
X16685Y109153D01*
X16741Y109236D01*
X16812Y109307D01*
X17480Y110307D01*
X17518Y110399D01*
X17574Y110483D01*
X18034Y111594D01*
X18054Y111692D01*
X18092Y111785D01*
X18327Y112964D01*
Y113064D01*
X18346Y113163D01*
Y113764D01*
Y114365D01*
X18327Y114463D01*
Y114564D01*
X18092Y115743D01*
X18054Y115835D01*
X18034Y115934D01*
X17574Y117044D01*
X17518Y117128D01*
X17480Y117221D01*
X16812Y118220D01*
X16741Y118291D01*
X16685Y118375D01*
X15835Y119225D01*
X15752Y119281D01*
X15681Y119351D01*
X14681Y120019D01*
X14589Y120058D01*
X14505Y120114D01*
X13395Y120574D01*
X13296Y120593D01*
X13203Y120632D01*
X12024Y120866D01*
X11924D01*
X11825Y120886D01*
D02*
G37*
G36*
X121558Y108500D02*
X120842D01*
X120180Y108226D01*
X119674Y107720D01*
X119400Y107058D01*
Y106342D01*
X119674Y105680D01*
X120180Y105174D01*
X120842Y104900D01*
X121558D01*
X122220Y105174D01*
X122726Y105680D01*
X123000Y106342D01*
Y107058D01*
X122726Y107720D01*
X122220Y108226D01*
X121558Y108500D01*
D02*
G37*
G36*
X138058Y106000D02*
X137342D01*
X136680Y105726D01*
X136174Y105220D01*
X135900Y104558D01*
Y103842D01*
X136174Y103180D01*
X136680Y102674D01*
X137342Y102400D01*
X138058D01*
X138720Y102674D01*
X139226Y103180D01*
X139500Y103842D01*
Y104558D01*
X139226Y105220D01*
X138720Y105726D01*
X138058Y106000D01*
D02*
G37*
G36*
X121558Y104069D02*
X120842D01*
X120180Y103795D01*
X119674Y103288D01*
X119400Y102627D01*
Y101910D01*
X119674Y101249D01*
X120180Y100743D01*
X120842Y100469D01*
X121558D01*
X122220Y100743D01*
X122726Y101249D01*
X123000Y101910D01*
Y102627D01*
X122726Y103288D01*
X122220Y103795D01*
X121558Y104069D01*
D02*
G37*
G36*
X217758Y81800D02*
X217042D01*
X216380Y81526D01*
X215874Y81020D01*
X215600Y80358D01*
Y79642D01*
X215874Y78980D01*
X216380Y78474D01*
X217042Y78200D01*
X217758D01*
X218420Y78474D01*
X218926Y78980D01*
X219200Y79642D01*
Y80358D01*
X218926Y81020D01*
X218420Y81526D01*
X217758Y81800D01*
D02*
G37*
G36*
X217558Y73900D02*
X216842D01*
X216180Y73626D01*
X215674Y73120D01*
X215400Y72458D01*
Y71742D01*
X215674Y71080D01*
X216180Y70574D01*
X216842Y70300D01*
X217558D01*
X218220Y70574D01*
X218726Y71080D01*
X219000Y71742D01*
Y72458D01*
X218726Y73120D01*
X218220Y73626D01*
X217558Y73900D01*
D02*
G37*
G36*
X208958D02*
X208242D01*
X207580Y73626D01*
X207074Y73120D01*
X206800Y72458D01*
Y71742D01*
X207074Y71080D01*
X207580Y70574D01*
X208242Y70300D01*
X208958D01*
X209620Y70574D01*
X210126Y71080D01*
X210400Y71742D01*
Y72458D01*
X210126Y73120D01*
X209620Y73626D01*
X208958Y73900D01*
D02*
G37*
G36*
X69858Y68100D02*
X69142D01*
X68480Y67826D01*
X67974Y67320D01*
X67700Y66658D01*
Y65942D01*
X67974Y65280D01*
X68480Y64774D01*
X69142Y64500D01*
X69858D01*
X70520Y64774D01*
X71026Y65280D01*
X71300Y65942D01*
Y66658D01*
X71026Y67320D01*
X70520Y67826D01*
X69858Y68100D01*
D02*
G37*
G36*
X198658Y67600D02*
X197942D01*
X197280Y67326D01*
X196774Y66820D01*
X196500Y66158D01*
Y65442D01*
X196774Y64780D01*
X197280Y64274D01*
X197942Y64000D01*
X198658D01*
X199320Y64274D01*
X199826Y64780D01*
X200100Y65442D01*
Y66158D01*
X199826Y66820D01*
X199320Y67326D01*
X198658Y67600D01*
D02*
G37*
G36*
X187558Y67500D02*
X186842D01*
X186180Y67226D01*
X185674Y66720D01*
X185400Y66058D01*
Y65342D01*
X185674Y64680D01*
X186180Y64174D01*
X186842Y63900D01*
X187558D01*
X188220Y64174D01*
X188726Y64680D01*
X189000Y65342D01*
Y66058D01*
X188726Y66720D01*
X188220Y67226D01*
X187558Y67500D01*
D02*
G37*
G36*
X55158Y65100D02*
X54442D01*
X53780Y64826D01*
X53274Y64320D01*
X53000Y63658D01*
Y62942D01*
X53274Y62280D01*
X53780Y61774D01*
X54442Y61500D01*
X55158D01*
X55820Y61774D01*
X56326Y62280D01*
X56600Y62942D01*
Y63658D01*
X56326Y64320D01*
X55820Y64826D01*
X55158Y65100D01*
D02*
G37*
G36*
X225458Y63000D02*
X224742D01*
X224080Y62726D01*
X223574Y62220D01*
X223300Y61558D01*
Y60842D01*
X223574Y60180D01*
X224080Y59674D01*
X224742Y59400D01*
X225458D01*
X226120Y59674D01*
X226626Y60180D01*
X226900Y60842D01*
Y61558D01*
X226626Y62220D01*
X226120Y62726D01*
X225458Y63000D01*
D02*
G37*
G36*
X68258Y60800D02*
X67542D01*
X66880Y60526D01*
X66374Y60020D01*
X66100Y59358D01*
Y58642D01*
X66374Y57980D01*
X66880Y57474D01*
X67542Y57200D01*
X68258D01*
X68920Y57474D01*
X69426Y57980D01*
X69700Y58642D01*
Y59358D01*
X69426Y60020D01*
X68920Y60526D01*
X68258Y60800D01*
D02*
G37*
G36*
X63158Y58500D02*
X62442D01*
X61780Y58226D01*
X61274Y57720D01*
X61000Y57058D01*
Y56342D01*
X61274Y55680D01*
X61780Y55174D01*
X62442Y54900D01*
X63158D01*
X63820Y55174D01*
X64326Y55680D01*
X64600Y56342D01*
Y57058D01*
X64326Y57720D01*
X63820Y58226D01*
X63158Y58500D01*
D02*
G37*
G36*
X65919Y55039D02*
X65203D01*
X64542Y54765D01*
X64035Y54258D01*
X63761Y53597D01*
Y52881D01*
X64035Y52219D01*
X64542Y51713D01*
X65203Y51439D01*
X65919D01*
X66581Y51713D01*
X67087Y52219D01*
X67361Y52881D01*
Y53597D01*
X67087Y54258D01*
X66581Y54765D01*
X65919Y55039D01*
D02*
G37*
G36*
X56958Y50800D02*
X56242D01*
X55580Y50526D01*
X55074Y50020D01*
X54800Y49358D01*
Y48642D01*
X55074Y47980D01*
X55580Y47474D01*
X56242Y47200D01*
X56958D01*
X57620Y47474D01*
X58126Y47980D01*
X58400Y48642D01*
Y49358D01*
X58126Y50020D01*
X57620Y50526D01*
X56958Y50800D01*
D02*
G37*
G36*
X207875Y45228D02*
X207159D01*
X206498Y44954D01*
X205991Y44447D01*
X205717Y43786D01*
Y43069D01*
X205991Y42408D01*
X206498Y41902D01*
X207159Y41628D01*
X207875D01*
X208537Y41902D01*
X209043Y42408D01*
X209317Y43069D01*
Y43786D01*
X209043Y44447D01*
X208537Y44954D01*
X207875Y45228D01*
D02*
G37*
G36*
X222458Y42300D02*
X221742D01*
X221080Y42026D01*
X220574Y41520D01*
X220300Y40858D01*
Y40142D01*
X220574Y39480D01*
X221080Y38974D01*
X221742Y38700D01*
X222458D01*
X223120Y38974D01*
X223626Y39480D01*
X223900Y40142D01*
Y40858D01*
X223626Y41520D01*
X223120Y42026D01*
X222458Y42300D01*
D02*
G37*
G36*
X207875Y34617D02*
X207159D01*
X206498Y34343D01*
X205991Y33837D01*
X205717Y33175D01*
Y32459D01*
X205991Y31798D01*
X206498Y31291D01*
X207159Y31017D01*
X207875D01*
X208537Y31291D01*
X209043Y31798D01*
X209317Y32459D01*
Y33175D01*
X209043Y33837D01*
X208537Y34343D01*
X207875Y34617D01*
D02*
G37*
G36*
X250014Y18523D02*
X248812D01*
X248714Y18504D01*
X248613D01*
X247434Y18269D01*
X247342Y18231D01*
X247243Y18211D01*
X246133Y17751D01*
X246049Y17696D01*
X245956Y17657D01*
X244957Y16989D01*
X244886Y16918D01*
X244802Y16862D01*
X243952Y16013D01*
X243897Y15929D01*
X243826Y15858D01*
X243158Y14859D01*
X243119Y14766D01*
X243064Y14682D01*
X242604Y13572D01*
X242584Y13473D01*
X242546Y13381D01*
X242311Y12201D01*
Y12101D01*
X242291Y12003D01*
Y11402D01*
Y10801D01*
X242311Y10702D01*
Y10602D01*
X242546Y9423D01*
X242584Y9330D01*
X242604Y9231D01*
X243064Y8121D01*
X243119Y8037D01*
X243158Y7945D01*
X243826Y6945D01*
X243897Y6874D01*
X243952Y6791D01*
X244802Y5941D01*
X244886Y5885D01*
X244957Y5814D01*
X245956Y5146D01*
X246049Y5108D01*
X246133Y5052D01*
X247243Y4592D01*
X247342Y4572D01*
X247434Y4534D01*
X248613Y4299D01*
X248714D01*
X248812Y4280D01*
X250014D01*
X250113Y4299D01*
X250213D01*
X251392Y4534D01*
X251485Y4572D01*
X251584Y4592D01*
X252694Y5052D01*
X252778Y5108D01*
X252870Y5146D01*
X253870Y5814D01*
X253941Y5885D01*
X254024Y5941D01*
X254874Y6791D01*
X254930Y6874D01*
X255001Y6945D01*
X255669Y7945D01*
X255707Y8037D01*
X255763Y8121D01*
X256223Y9231D01*
X256243Y9330D01*
X256281Y9423D01*
X256516Y10602D01*
Y10702D01*
X256535Y10801D01*
Y11402D01*
Y12003D01*
X256516Y12101D01*
Y12201D01*
X256281Y13381D01*
X256243Y13473D01*
X256223Y13572D01*
X255763Y14682D01*
X255707Y14766D01*
X255669Y14859D01*
X255001Y15858D01*
X254930Y15929D01*
X254874Y16013D01*
X254024Y16862D01*
X253941Y16918D01*
X253870Y16989D01*
X252870Y17657D01*
X252778Y17696D01*
X252694Y17751D01*
X251584Y18211D01*
X251485Y18231D01*
X251392Y18269D01*
X250213Y18504D01*
X250113D01*
X250014Y18523D01*
D02*
G37*
G36*
X11825D02*
X10623D01*
X10525Y18504D01*
X10424D01*
X9245Y18269D01*
X9153Y18231D01*
X9054Y18211D01*
X7944Y17751D01*
X7860Y17696D01*
X7767Y17657D01*
X6768Y16989D01*
X6697Y16918D01*
X6613Y16862D01*
X5763Y16013D01*
X5708Y15929D01*
X5637Y15858D01*
X4969Y14859D01*
X4930Y14766D01*
X4875Y14682D01*
X4415Y13572D01*
X4395Y13473D01*
X4357Y13381D01*
X4122Y12201D01*
Y12101D01*
X4103Y12003D01*
Y11402D01*
Y10801D01*
X4122Y10702D01*
Y10602D01*
X4357Y9423D01*
X4395Y9330D01*
X4415Y9231D01*
X4875Y8121D01*
X4930Y8037D01*
X4969Y7945D01*
X5637Y6945D01*
X5708Y6874D01*
X5763Y6791D01*
X6613Y5941D01*
X6697Y5885D01*
X6768Y5814D01*
X7767Y5146D01*
X7860Y5108D01*
X7944Y5052D01*
X9054Y4592D01*
X9153Y4572D01*
X9245Y4534D01*
X10424Y4299D01*
X10525D01*
X10623Y4280D01*
X11825D01*
X11924Y4299D01*
X12024D01*
X13203Y4534D01*
X13296Y4572D01*
X13395Y4592D01*
X14505Y5052D01*
X14589Y5108D01*
X14681Y5146D01*
X15681Y5814D01*
X15752Y5885D01*
X15835Y5941D01*
X16685Y6791D01*
X16741Y6874D01*
X16812Y6945D01*
X17480Y7945D01*
X17518Y8037D01*
X17574Y8121D01*
X18034Y9231D01*
X18054Y9330D01*
X18092Y9423D01*
X18327Y10602D01*
Y10702D01*
X18346Y10801D01*
Y11402D01*
Y12003D01*
X18327Y12101D01*
Y12201D01*
X18092Y13381D01*
X18054Y13473D01*
X18034Y13572D01*
X17574Y14682D01*
X17518Y14766D01*
X17480Y14859D01*
X16812Y15858D01*
X16741Y15929D01*
X16685Y16013D01*
X15835Y16862D01*
X15752Y16918D01*
X15681Y16989D01*
X14681Y17657D01*
X14589Y17696D01*
X14505Y17751D01*
X13395Y18211D01*
X13296Y18231D01*
X13203Y18269D01*
X12024Y18504D01*
X11924D01*
X11825Y18523D01*
D02*
G37*
%LPD*%
D58*
X215400Y47200D02*
D03*
X198300Y65800D02*
D03*
X187200Y65700D02*
D03*
X75800Y74400D02*
D03*
X87968Y80005D02*
D03*
X83568D02*
D03*
X79232Y80753D02*
D03*
X80035Y74573D02*
D03*
X84391Y75195D02*
D03*
X88791D02*
D03*
X18874Y81741D02*
D03*
X17342Y77617D02*
D03*
X19368Y73711D02*
D03*
X23616Y72562D02*
D03*
X27335Y74913D02*
D03*
X31689Y75547D02*
D03*
X36089D02*
D03*
X40202Y73983D02*
D03*
X47600Y75200D02*
D03*
X56960Y75547D02*
D03*
X61360D02*
D03*
X65760D02*
D03*
X70160D02*
D03*
X75868Y80753D02*
D03*
X71486Y80358D02*
D03*
X67086D02*
D03*
X62686D02*
D03*
X58286D02*
D03*
X53886D02*
D03*
X49486D02*
D03*
X45088Y80484D02*
D03*
X40689Y80358D02*
D03*
X36289D02*
D03*
X31889D02*
D03*
X27503Y80696D02*
D03*
X23955Y83298D02*
D03*
X108600Y37300D02*
D03*
X116925D02*
D03*
X125250D02*
D03*
X133575D02*
D03*
X141900D02*
D03*
X108700Y29000D02*
D03*
X117025D02*
D03*
X125350D02*
D03*
X133675D02*
D03*
X142000D02*
D03*
X108700Y45700D02*
D03*
X117025D02*
D03*
X125350D02*
D03*
X133675D02*
D03*
X142000D02*
D03*
X108700Y54100D02*
D03*
X117025D02*
D03*
X125350D02*
D03*
X133675D02*
D03*
X142000D02*
D03*
X108600Y62100D02*
D03*
X116925D02*
D03*
X125250D02*
D03*
X133575D02*
D03*
X141900D02*
D03*
X108600Y70400D02*
D03*
X116925D02*
D03*
X125250D02*
D03*
X133575D02*
D03*
X141900D02*
D03*
Y78800D02*
D03*
X133575D02*
D03*
X125250D02*
D03*
X116925D02*
D03*
X108600D02*
D03*
X259467Y120459D02*
D03*
Y110459D02*
D03*
Y100459D02*
D03*
Y90459D02*
D03*
Y80459D02*
D03*
Y70459D02*
D03*
Y60459D02*
D03*
Y50459D02*
D03*
Y40459D02*
D03*
Y30459D02*
D03*
Y20459D02*
D03*
Y10459D02*
D03*
X249467Y100459D02*
D03*
Y90459D02*
D03*
Y20459D02*
D03*
X239467Y120459D02*
D03*
Y110459D02*
D03*
Y100459D02*
D03*
Y90459D02*
D03*
Y60459D02*
D03*
Y50459D02*
D03*
Y20459D02*
D03*
Y10459D02*
D03*
X229467Y120459D02*
D03*
Y110459D02*
D03*
Y100459D02*
D03*
Y90459D02*
D03*
Y80459D02*
D03*
Y70459D02*
D03*
Y60459D02*
D03*
Y10459D02*
D03*
X219467Y120459D02*
D03*
Y110459D02*
D03*
Y100459D02*
D03*
Y90459D02*
D03*
X209467Y120459D02*
D03*
Y110459D02*
D03*
Y100459D02*
D03*
Y60459D02*
D03*
X199467Y120459D02*
D03*
Y110459D02*
D03*
Y80459D02*
D03*
Y30459D02*
D03*
X189467Y120459D02*
D03*
Y90459D02*
D03*
Y80459D02*
D03*
Y60459D02*
D03*
Y50459D02*
D03*
Y40459D02*
D03*
Y30459D02*
D03*
Y10459D02*
D03*
X179467Y120459D02*
D03*
Y90459D02*
D03*
Y60459D02*
D03*
Y50459D02*
D03*
Y40459D02*
D03*
Y20459D02*
D03*
X169467Y120459D02*
D03*
Y80459D02*
D03*
Y60459D02*
D03*
Y50459D02*
D03*
Y30459D02*
D03*
Y20459D02*
D03*
X159467Y120459D02*
D03*
Y90459D02*
D03*
Y80459D02*
D03*
Y70459D02*
D03*
Y40459D02*
D03*
Y30459D02*
D03*
Y20459D02*
D03*
X149467Y120459D02*
D03*
Y20459D02*
D03*
X139467Y120459D02*
D03*
Y20459D02*
D03*
X129467Y120459D02*
D03*
Y20459D02*
D03*
X119467Y120459D02*
D03*
Y110459D02*
D03*
Y20459D02*
D03*
X109467Y120459D02*
D03*
Y20459D02*
D03*
X99467Y120459D02*
D03*
Y110459D02*
D03*
Y20459D02*
D03*
X89467Y120459D02*
D03*
Y110459D02*
D03*
Y100459D02*
D03*
Y90459D02*
D03*
Y50459D02*
D03*
Y40459D02*
D03*
Y30459D02*
D03*
Y10459D02*
D03*
X79467Y120459D02*
D03*
Y110459D02*
D03*
Y100459D02*
D03*
Y90459D02*
D03*
Y20459D02*
D03*
Y10459D02*
D03*
X69467Y120459D02*
D03*
Y110459D02*
D03*
Y100459D02*
D03*
Y90459D02*
D03*
Y50459D02*
D03*
Y40459D02*
D03*
Y20459D02*
D03*
X59467Y120459D02*
D03*
Y110459D02*
D03*
Y100459D02*
D03*
Y90459D02*
D03*
Y10459D02*
D03*
X49467Y120459D02*
D03*
Y110459D02*
D03*
Y100459D02*
D03*
Y90459D02*
D03*
Y40459D02*
D03*
Y30459D02*
D03*
Y20459D02*
D03*
Y10459D02*
D03*
X39467Y120459D02*
D03*
Y110459D02*
D03*
Y100459D02*
D03*
Y90459D02*
D03*
Y70459D02*
D03*
Y60459D02*
D03*
Y50459D02*
D03*
Y40459D02*
D03*
Y30459D02*
D03*
Y20459D02*
D03*
Y10459D02*
D03*
X29467Y120459D02*
D03*
Y110459D02*
D03*
Y100459D02*
D03*
Y70459D02*
D03*
Y60459D02*
D03*
Y50459D02*
D03*
Y40459D02*
D03*
Y30459D02*
D03*
Y20459D02*
D03*
Y10459D02*
D03*
X19467Y120459D02*
D03*
Y110459D02*
D03*
Y100459D02*
D03*
Y60459D02*
D03*
Y50459D02*
D03*
Y40459D02*
D03*
Y30459D02*
D03*
Y20459D02*
D03*
X9467Y100459D02*
D03*
Y90459D02*
D03*
Y80459D02*
D03*
Y70459D02*
D03*
Y60459D02*
D03*
Y50459D02*
D03*
Y40459D02*
D03*
Y30459D02*
D03*
Y20459D02*
D03*
X193900Y56000D02*
D03*
X225100Y61200D02*
D03*
X67900Y59000D02*
D03*
X56600Y49000D02*
D03*
X62800Y56700D02*
D03*
X65561Y53239D02*
D03*
X54800Y63300D02*
D03*
X69500Y66300D02*
D03*
X208600Y72100D02*
D03*
X137700Y104200D02*
D03*
Y111200D02*
D03*
X217400Y80000D02*
D03*
X121200Y102269D02*
D03*
Y106700D02*
D03*
X207517Y32817D02*
D03*
X217200Y72100D02*
D03*
X207517Y43428D02*
D03*
X222100Y40500D02*
D03*
M02*
